# S9S_MB_2U (Grand Teton) — schematic netlist excerpt (pin names and nets, part order shuffled) for the footprints in the layout excerpt that follows; sources: Cadence DE-HDL packaged netlist, KiCad conversion of 03242023_DA0F0TMBIJ0_F0T_Motherboard_J_brd_V01_OCP.brd

C1751  Q_CAP  0.1UF 25V 10% X7R  pkg 0402  page 245 : A = P3V3_AUX ; B = GND
R2815  Q_RES  100K 1% EMPTY  pkg 0402LF  page 151 : A = P3V3_AUX ; B = BMC_MONITER_R

(kicad_pcb
	(version 20260206)
	(generator "pcbnew")
	(generator_version "10.0")
	(general
		(thickness 1.6)
		(legacy_teardrops no)
	)
	(paper "A4")
	(title_block
		(title "03242023_DA0F0TMBIJ0_F0T_Motherboard_J_brd_V01_OCP.brd")
		(comment 1 "Grand Teton / footprints 3408-3409 of 6105")
	)
	(layers
		(0 "F.Cu" signal "TOP")
		(4 "In1.Cu" signal "GND")
		(6 "In2.Cu" signal "IN1")
		(8 "In3.Cu" signal "GND1")
		(10 "In4.Cu" signal "IN2")
		(12 "In5.Cu" signal "GND2")
		(14 "In6.Cu" signal "IN3")
		(16 "In7.Cu" signal "GND3")
		(18 "In8.Cu" signal "VCC")
		(20 "In9.Cu" signal "VCC1")
		(22 "In10.Cu" signal "GND4")
		(24 "In11.Cu" signal "IN4")
		(26 "In12.Cu" signal "GND5")
		(28 "In13.Cu" signal "IN5")
		(30 "In14.Cu" signal "GND6")
		(32 "In15.Cu" signal "IN6")
		(34 "In16.Cu" signal "GND7")
		(2 "B.Cu" signal "BOTTOM")
		(9 "F.Adhes" user "F.Adhesive")
		(11 "B.Adhes" user "B.Adhesive")
		(13 "F.Paste" user "Package Geometry/Pastemask Top")
		(15 "B.Paste" user "Package Geometry/Pastemask Bottom")
		(5 "F.SilkS" user "Ref Des/Silkscreen Top")
		(7 "B.SilkS" user "Ref Des/Silkscreen Bottom")
		(1 "F.Mask" user "Board Geometry/Soldermask Top")
		(3 "B.Mask" user "Board Geometry/Soldermask Bottom")
		(17 "Dwgs.User" user "User.Drawings")
		(19 "Cmts.User" user "User.Comments")
		(21 "Eco1.User" user "User.Eco1")
		(23 "Eco2.User" user "User.Eco2")
		(25 "Edge.Cuts" user "Board Geometry/Outline")
		(27 "Margin" user)
		(31 "F.CrtYd" user "Package Geometry/Place Bound Top")
		(29 "B.CrtYd" user "Package Geometry/Place Bound Bottom")
		(35 "F.Fab" user "Ref Des/Assembly Top")
		(33 "B.Fab" user "Ref Des/Assembly Bottom")
	)
	(footprint ""
		(layer "F.Cu")
		(at 180.776626 -416.903154 -90)
		(property "Reference" "C1751"
			(at 0 0 270)
			(layer "F.SilkS")
			(hide yes)
			(effects
				(font
					(size 1.27 1.27)
				)
			)
		)
		(property "Value" ""
			(at 0 0 270)
			(layer "F.Fab")
			(effects
				(font
					(size 1.27 1.27)
				)
			)
		)
		(duplicate_pad_numbers_are_jumpers no)
		(fp_line
			(start -0.7874 0.4064)
			(end -0.7874 -0.4064)
			(stroke
				(width 0.1524)
				(type default)
			)
			(layer "F.SilkS")
		)
		(fp_line
			(start 0.7874 0.4064)
			(end -0.7874 0.4064)
			(stroke
				(width 0.1524)
				(type default)
			)
			(layer "F.SilkS")
		)
		(fp_line
			(start -0.7874 -0.4064)
			(end 0.7874 -0.4064)
			(stroke
				(width 0.1524)
				(type default)
			)
			(layer "F.SilkS")
		)
		(fp_line
			(start 0.7874 -0.4064)
			(end 0.7874 0.4064)
			(stroke
				(width 0.1524)
				(type default)
			)
			(layer "F.SilkS")
		)
		(fp_line
			(start -0.67945 0.3048)
			(end -0.67945 -0.305054)
			(stroke
				(width 0.1)
				(type default)
			)
			(layer "F.Fab")
		)
		(fp_line
			(start -0.12065 0.3048)
			(end -0.67945 0.3048)
			(stroke
				(width 0.1)
				(type default)
			)
			(layer "F.Fab")
		)
		(fp_line
			(start 0.120396 0.3048)
			(end 0.120396 0.2794)
			(stroke
				(width 0.1)
				(type default)
			)
			(layer "F.Fab")
		)
		(fp_line
			(start 0.67945 0.3048)
			(end 0.120396 0.3048)
			(stroke
				(width 0.1)
				(type default)
			)
			(layer "F.Fab")
		)
		(fp_line
			(start -0.12065 0.2794)
			(end -0.12065 0.3048)
			(stroke
				(width 0.1)
				(type default)
			)
			(layer "F.Fab")
		)
		(fp_line
			(start 0.120396 0.2794)
			(end -0.12065 0.2794)
			(stroke
				(width 0.1)
				(type default)
			)
			(layer "F.Fab")
		)
		(fp_line
			(start -0.12065 -0.2794)
			(end 0.12065 -0.2794)
			(stroke
				(width 0.1)
				(type default)
			)
			(layer "F.Fab")
		)
		(fp_line
			(start 0.12065 -0.2794)
			(end 0.12065 -0.3048)
			(stroke
				(width 0.1)
				(type default)
			)
			(layer "F.Fab")
		)
		(fp_line
			(start 0.12065 -0.3048)
			(end 0.67945 -0.3048)
			(stroke
				(width 0.1)
				(type default)
			)
			(layer "F.Fab")
		)
		(fp_line
			(start 0.67945 -0.3048)
			(end 0.67945 0.3048)
			(stroke
				(width 0.1)
				(type default)
			)
			(layer "F.Fab")
		)
		(fp_line
			(start -0.67945 -0.305054)
			(end -0.12065 -0.305054)
			(stroke
				(width 0.1)
				(type default)
			)
			(layer "F.Fab")
		)
		(fp_line
			(start -0.12065 -0.305054)
			(end -0.12065 -0.2794)
			(stroke
				(width 0.1)
				(type default)
			)
			(layer "F.Fab")
		)
		(pad "1" smd circle
			(at -0.40005 0 270)
			(size 0 0)
			(layers "F.Cu" "F.Mask" "F.Paste")
			(net "P3V3_AUX")
		)
		(pad "2" smd circle
			(at 0.40005 0 270)
			(size 0 0)
			(layers "F.Cu" "F.Mask" "F.Paste")
			(net "GND")
		)
	)
	(footprint ""
		(layer "F.Cu")
		(at 169.44848 -424.906948)
		(property "Reference" "R2815"
			(at 0 0 0)
			(layer "F.SilkS")
			(hide yes)
			(effects
				(font
					(size 1.27 1.27)
				)
			)
		)
		(property "Value" ""
			(at 0 0 0)
			(layer "F.Fab")
			(effects
				(font
					(size 1.27 1.27)
				)
			)
		)
		(duplicate_pad_numbers_are_jumpers no)
		(fp_line
			(start -0.7874 -0.4064)
			(end 0.7874 -0.4064)
			(stroke
				(width 0.1524)
				(type default)
			)
			(layer "F.SilkS")
		)
		(fp_line
			(start -0.7874 0.4064)
			(end -0.7874 -0.4064)
			(stroke
				(width 0.1524)
				(type default)
			)
			(layer "F.SilkS")
		)
		(fp_line
			(start 0.7874 -0.4064)
			(end 0.7874 0.4064)
			(stroke
				(width 0.1524)
				(type default)
			)
			(layer "F.SilkS")
		)
		(fp_line
			(start 0.7874 0.4064)
			(end -0.7874 0.4064)
			(stroke
				(width 0.1524)
				(type default)
			)
			(layer "F.SilkS")
		)
		(fp_line
			(start -0.67945 -0.305054)
			(end -0.12065 -0.305054)
			(stroke
				(width 0.1)
				(type default)
			)
			(layer "F.Fab")
		)
		(fp_line
			(start -0.67945 0.3048)
			(end -0.67945 -0.305054)
			(stroke
				(width 0.1)
				(type default)
			)
			(layer "F.Fab")
		)
		(fp_line
			(start -0.12065 -0.305054)
			(end -0.12065 -0.2794)
			(stroke
				(width 0.1)
				(type default)
			)
			(layer "F.Fab")
		)
		(fp_line
			(start -0.12065 -0.2794)
			(end 0.12065 -0.2794)
			(stroke
				(width 0.1)
				(type default)
			)
			(layer "F.Fab")
		)
		(fp_line
			(start -0.12065 0.2794)
			(end -0.12065 0.3048)
			(stroke
				(width 0.1)
				(type default)
			)
			(layer "F.Fab")
		)
		(fp_line
			(start -0.12065 0.3048)
			(end -0.67945 0.3048)
			(stroke
				(width 0.1)
				(type default)
			)
			(layer "F.Fab")
		)
		(fp_line
			(start 0.120396 0.2794)
			(end -0.12065 0.2794)
			(stroke
				(width 0.1)
				(type default)
			)
			(layer "F.Fab")
		)
		(fp_line
			(start 0.120396 0.3048)
			(end 0.120396 0.2794)
			(stroke
				(width 0.1)
				(type default)
			)
			(layer "F.Fab")
		)
		(fp_line
			(start 0.12065 -0.3048)
			(end 0.67945 -0.3048)
			(stroke
				(width 0.1)
				(type default)
			)
			(layer "F.Fab")
		)
		(fp_line
			(start 0.12065 -0.2794)
			(end 0.12065 -0.3048)
			(stroke
				(width 0.1)
				(type default)
			)
			(layer "F.Fab")
		)
		(fp_line
			(start 0.67945 -0.3048)
			(end 0.67945 0.3048)
			(stroke
				(width 0.1)
				(type default)
			)
			(layer "F.Fab")
		)
		(fp_line
			(start 0.67945 0.3048)
			(end 0.120396 0.3048)
			(stroke
				(width 0.1)
				(type default)
			)
			(layer "F.Fab")
		)
		(pad "1" smd circle
			(at -0.40005 0)
			(size 0 0)
			(layers "F.Cu" "F.Mask" "F.Paste")
			(net "P3V3_AUX")
		)
		(pad "2" smd circle
			(at 0.40005 0)
			(size 0 0)
			(layers "F.Cu" "F.Mask" "F.Paste")
			(net "BMC_MONITER_R")
		)
	)
)
